(kicad_pcb
	(version 20260206)
	(generator "pcbnew")
	(generator_version "10.0")
	(general
		(thickness 1.6)
		(legacy_teardrops no)
	)
	(paper "A4")
	(title_block
		(title "panther-plus-userver — 13130-1b_20150205.brd")
		(comment 1 "Honey Badger (Wiwynn) / footprints 1457-1464 of 1509")
	)
	(layers
		(0 "F.Cu" signal "TOP")
		(4 "In1.Cu" signal "L2")
		(6 "In2.Cu" signal "L3")
		(8 "In3.Cu" signal "L4")
		(10 "In4.Cu" signal "L5")
		(12 "In5.Cu" signal "L6")
		(14 "In6.Cu" signal "L7")
		(16 "In7.Cu" signal "L8")
		(18 "In8.Cu" signal "L9")
		(20 "In9.Cu" signal "L10")
		(22 "In10.Cu" signal "L11")
		(2 "B.Cu" signal "BOTTOM")
		(9 "F.Adhes" user "F.Adhesive")
		(11 "B.Adhes" user "B.Adhesive")
		(13 "F.Paste" user "Package Geometry/Pastemask Top")
		(15 "B.Paste" user "Package Geometry/Pastemask Bottom")
		(5 "F.SilkS" user "Ref Des/Silkscreen Top")
		(7 "B.SilkS" user "Ref Des/Silkscreen Bottom")
		(1 "F.Mask" user "Board Geometry/Soldermask Top")
		(3 "B.Mask" user "Board Geometry/Soldermask Bottom")
		(17 "Dwgs.User" user "User.Drawings")
		(19 "Cmts.User" user "User.Comments")
		(21 "Eco1.User" user "User.Eco1")
		(23 "Eco2.User" user "User.Eco2")
		(25 "Edge.Cuts" user "Board Geometry/Outline")
		(27 "Margin" user)
		(31 "F.CrtYd" user "Package Geometry/Place Bound Top")
		(29 "B.CrtYd" user "Package Geometry/Place Bound Bottom")
		(35 "F.Fab" user "Ref Des/Assembly Top")
		(33 "B.Fab" user "Ref Des/Assembly Bottom")
	)
	(footprint ""
		(layer "B.Cu")
		(at 22.3012 -54.229 180)
		(property "Reference" "PR74"
			(at 0 0 0)
			(layer "B.SilkS")
			(hide yes)
			(effects
				(font
					(size 1.27 1.27)
				)
				(justify mirror)
			)
		)
		(property "Value" "0R2J-2-GP"
			(at -1.7907 -1.1176 180)
			(unlocked yes)
			(layer "B.Fab")
			(hide yes)
			(effects
				(font
					(size 1.016 1.016)
					(thickness 0.1524)
				)
				(justify mirror)
			)
		)
		(property "Device Type" "R402H16"
			(at -1.7907 -2.6416 180)
			(unlocked yes)
			(layer "B.Fab")
			(hide yes)
			(effects
				(font
					(size 1.016 1.016)
					(thickness 0.1524)
				)
				(justify mirror)
			)
		)
		(duplicate_pad_numbers_are_jumpers no)
		(fp_rect
			(start 0.381 0.8382)
			(end -0.381 -0.8382)
			(stroke
				(width 0)
				(type default)
			)
			(fill no)
			(layer "B.CrtYd")
		)
		(fp_rect
			(start 0.381 0.8382)
			(end -0.381 -0.8382)
			(stroke
				(width 0)
				(type default)
			)
			(fill no)
			(layer "B.Fab")
		)
		(pad "1" smd custom
			(at 0 -0.4318)
			(size 0.127 0.127)
			(layers "B.Cu" "B.Mask" "B.Paste")
			(net "PVCCP_ISEN2")
			(options
				(clearance outline)
				(anchor circle)
			)
			(primitives
				(gr_poly
					(pts
						(arc
							(start -0.2032 0.2794)
							(mid -0.239121 0.264521)
							(end -0.254 0.2286)
						)
						(arc
							(start -0.254 -0.2286)
							(mid -0.239121 -0.264521)
							(end -0.2032 -0.2794)
						)
						(arc
							(start 0.2032 -0.2794)
							(mid 0.239121 -0.264521)
							(end 0.254 -0.2286)
						)
						(arc
							(start 0.254 0.2286)
							(mid 0.239121 0.264521)
							(end 0.2032 0.2794)
						)
					)
					(width 0)
					(fill yes)
				)
			)
		)
		(pad "2" smd custom
			(at 0 0.4318)
			(size 0.127 0.127)
			(layers "B.Cu" "B.Mask" "B.Paste")
			(net "VR_PVCCP_PVNN_VDD")
			(options
				(clearance outline)
				(anchor circle)
			)
			(primitives
				(gr_poly
					(pts
						(arc
							(start -0.2032 0.2794)
							(mid -0.239121 0.264521)
							(end -0.254 0.2286)
						)
						(arc
							(start -0.254 -0.2286)
							(mid -0.239121 -0.264521)
							(end -0.2032 -0.2794)
						)
						(arc
							(start 0.2032 -0.2794)
							(mid 0.239121 -0.264521)
							(end 0.254 -0.2286)
						)
						(arc
							(start 0.254 0.2286)
							(mid 0.239121 0.264521)
							(end 0.2032 0.2794)
						)
					)
					(width 0)
					(fill yes)
				)
			)
		)
	)
	(footprint ""
		(layer "B.Cu")
		(at 91.845384 -51.755802 -90)
		(property "Reference" "R278"
			(at 0 0 90)
			(layer "B.SilkS")
			(hide yes)
			(effects
				(font
					(size 1.27 1.27)
				)
				(justify mirror)
			)
		)
		(property "Value" "100R3F-1-GP"
			(at 0.0254 -2.5146 270)
			(unlocked yes)
			(layer "B.Fab")
			(hide yes)
			(effects
				(font
					(size 1.016 1.016)
					(thickness 0.1524)
				)
				(justify mirror)
			)
		)
		(property "Device Type" "R603H22"
			(at 0.0254 -4.0386 270)
			(unlocked yes)
			(layer "B.Fab")
			(hide yes)
			(effects
				(font
					(size 1.016 1.016)
					(thickness 0.1524)
				)
				(justify mirror)
			)
		)
		(duplicate_pad_numbers_are_jumpers no)
		(fp_line
			(start -0.4318 0)
			(end -0.2032 0)
			(stroke
				(width 0.2032)
				(type default)
			)
			(layer "B.SilkS")
		)
		(fp_line
			(start 0.2032 0)
			(end 0.4191 0)
			(stroke
				(width 0.2032)
				(type default)
			)
			(layer "B.SilkS")
		)
		(fp_rect
			(start 0.635 1.1811)
			(end -0.635 -1.1811)
			(stroke
				(width 0)
				(type default)
			)
			(fill no)
			(layer "B.CrtYd")
		)
		(fp_rect
			(start 0.635 1.1811)
			(end -0.635 -1.1811)
			(stroke
				(width 0)
				(type default)
			)
			(fill no)
			(layer "B.Fab")
		)
		(pad "1" smd custom
			(at 0 -0.6604 90)
			(size 0.19685 0.19685)
			(layers "B.Cu" "B.Mask" "B.Paste")
			(net "PCIE_OBS_P")
			(options
				(clearance outline)
				(anchor circle)
			)
			(primitives
				(gr_poly
					(pts
						(arc
							(start 0.508 0.2921)
							(mid 0.478242 0.363942)
							(end 0.4064 0.3937)
						)
						(arc
							(start -0.4064 0.3937)
							(mid -0.478242 0.363942)
							(end -0.508 0.2921)
						)
						(arc
							(start -0.508 -0.2921)
							(mid -0.478242 -0.363942)
							(end -0.4064 -0.3937)
						)
						(arc
							(start 0.4064 -0.3937)
							(mid 0.478242 -0.363942)
							(end 0.508 -0.2921)
						)
					)
					(width 0)
					(fill yes)
				)
			)
		)
		(pad "2" smd custom
			(at 0 0.6604 90)
			(size 0.19685 0.19685)
			(layers "B.Cu" "B.Mask" "B.Paste")
			(net "PCIE_OBS_N")
			(options
				(clearance outline)
				(anchor circle)
			)
			(primitives
				(gr_poly
					(pts
						(arc
							(start 0.508 0.2921)
							(mid 0.478242 0.363942)
							(end 0.4064 0.3937)
						)
						(arc
							(start -0.4064 0.3937)
							(mid -0.478242 0.363942)
							(end -0.508 0.2921)
						)
						(arc
							(start -0.508 -0.2921)
							(mid -0.478242 -0.363942)
							(end -0.4064 -0.3937)
						)
						(arc
							(start 0.4064 -0.3937)
							(mid 0.478242 -0.363942)
							(end 0.508 -0.2921)
						)
					)
					(width 0)
					(fill yes)
				)
			)
		)
	)
	(footprint ""
		(layer "B.Cu")
		(at 69.1388 -34.3154 -90)
		(property "Reference" "U45"
			(at 0 0 90)
			(layer "B.SilkS")
			(hide yes)
			(effects
				(font
					(size 1.27 1.27)
				)
				(justify mirror)
			)
		)
		(property "Value" "SNLVC1G17DCKR-GP"
			(at 0 -8.0772 270)
			(unlocked yes)
			(layer "B.Fab")
			(hide yes)
			(effects
				(font
					(size 1.016 1.016)
					(thickness 0.1524)
				)
				(justify mirror)
			)
		)
		(property "Device Type" "SC70-5H44"
			(at 0 -9.6012 270)
			(unlocked yes)
			(layer "B.Fab")
			(hide yes)
			(effects
				(font
					(size 1.016 1.016)
					(thickness 0.1524)
				)
				(justify mirror)
			)
		)
		(duplicate_pad_numbers_are_jumpers no)
		(fp_line
			(start -1.0033 0.3302)
			(end 1.0033 0.3302)
			(stroke
				(width 0.1524)
				(type default)
			)
			(layer "B.SilkS")
		)
		(fp_line
			(start 1.0033 0.3302)
			(end 1.0033 -0.3302)
			(stroke
				(width 0.1524)
				(type default)
			)
			(layer "B.SilkS")
		)
		(fp_line
			(start -1.0033 -0.3302)
			(end -1.0033 0.3302)
			(stroke
				(width 0.1524)
				(type default)
			)
			(layer "B.SilkS")
		)
		(fp_line
			(start 1.0033 -0.3302)
			(end -1.0033 -0.3302)
			(stroke
				(width 0.1524)
				(type default)
			)
			(layer "B.SilkS")
		)
		(fp_poly
			(pts
				(xy 1.0033 1.4859) (xy 1.0033 0.8001) (xy 1.1811 0.8001) (xy 1.1811 -0.8001) (xy 1.0033 -0.8001)
				(xy 1.0033 -1.4859) (xy -1.0033 -1.4859) (xy -1.0033 -0.8001) (xy -1.1811 -0.8001) (xy -1.1811 0.8001)
				(xy -1.0033 0.8001) (xy -1.0033 1.4859) (xy -0.2921 1.4859) (xy -0.2921 0.8001) (xy 0.2921 0.8001)
				(xy 0.2921 1.4859)
			)
			(stroke
				(width 0)
				(type default)
			)
			(fill no)
			(layer "B.CrtYd")
		)
		(fp_poly
			(pts
				(xy 1.0033 1.4859) (xy 1.0033 0.8001) (xy 1.1811 0.8001) (xy 1.1811 -0.8001) (xy 1.0033 -0.8001)
				(xy 1.0033 -1.4859) (xy -1.0033 -1.4859) (xy -1.0033 -0.8001) (xy -1.1811 -0.8001) (xy -1.1811 0.8001)
				(xy -1.0033 0.8001) (xy -1.0033 1.4859) (xy -0.2921 1.4859) (xy -0.2921 0.8001) (xy 0.2921 0.8001)
				(xy 0.2921 1.4859)
			)
			(stroke
				(width 0)
				(type default)
			)
			(fill no)
			(layer "B.Fab")
		)
		(pad "1" smd rect
			(at -0.65024 -0.93472 90)
			(size 0.3556 0.762)
			(layers "B.Cu" "B.Mask" "B.Paste")
			(net "Net_68")
		)
		(pad "2" smd rect
			(at 0 -0.93472 90)
			(size 0.3556 0.762)
			(layers "B.Cu" "B.Mask" "B.Paste")
			(net "SRTCRST_BUF_IN#")
		)
		(pad "3" smd rect
			(at 0.65024 -0.93472 90)
			(size 0.3556 0.762)
			(layers "B.Cu" "B.Mask" "B.Paste")
			(net "GND")
		)
		(pad "4" smd rect
			(at 0.65024 0.93472 90)
			(size 0.3556 0.762)
			(layers "B.Cu" "B.Mask" "B.Paste")
			(net "SRTCRST#")
		)
		(pad "5" smd rect
			(at -0.65024 0.93472 90)
			(size 0.3556 0.762)
			(layers "B.Cu" "B.Mask" "B.Paste")
			(net "P3V3_STBY")
		)
	)
	(footprint ""
		(layer "B.Cu")
		(at 91.6813 -34.2138 -90)
		(property "Reference" "C213"
			(at 0 0 90)
			(layer "B.SilkS")
			(hide yes)
			(effects
				(font
					(size 1.27 1.27)
				)
				(justify mirror)
			)
		)
		(property "Value" "SC1U10V2KX-1GP"
			(at -1.1811 -2.7051 270)
			(unlocked yes)
			(layer "B.Fab")
			(hide yes)
			(effects
				(font
					(size 1.016 1.016)
					(thickness 0.1524)
				)
				(justify mirror)
			)
		)
		(property "Device Type" "C402H22"
			(at -1.1811 -4.2291 270)
			(unlocked yes)
			(layer "B.Fab")
			(hide yes)
			(effects
				(font
					(size 1.016 1.016)
					(thickness 0.1524)
				)
				(justify mirror)
			)
		)
		(duplicate_pad_numbers_are_jumpers no)
		(fp_rect
			(start 0.381 0.7366)
			(end -0.381 -0.7366)
			(stroke
				(width 0)
				(type default)
			)
			(fill no)
			(layer "B.CrtYd")
		)
		(fp_rect
			(start 0.381 0.7366)
			(end -0.381 -0.7366)
			(stroke
				(width 0)
				(type default)
			)
			(fill no)
			(layer "B.Fab")
		)
		(pad "1" smd custom
			(at 0 -0.4572 90)
			(size 0.1143 0.1143)
			(layers "B.Cu" "B.Mask" "B.Paste")
			(net "P1V0_STBY")
			(options
				(clearance outline)
				(anchor circle)
			)
			(primitives
				(gr_poly
					(pts
						(arc
							(start -0.254 0.1778)
							(mid -0.239121 0.213721)
							(end -0.2032 0.2286)
						)
						(arc
							(start 0.2032 0.2286)
							(mid 0.239121 0.213721)
							(end 0.254 0.1778)
						)
						(arc
							(start 0.254 -0.1778)
							(mid 0.239121 -0.213721)
							(end 0.2032 -0.2286)
						)
						(arc
							(start -0.2032 -0.2286)
							(mid -0.239121 -0.213721)
							(end -0.254 -0.1778)
						)
					)
					(width 0)
					(fill yes)
				)
			)
		)
		(pad "2" smd custom
			(at 0 0.4572 90)
			(size 0.1143 0.1143)
			(layers "B.Cu" "B.Mask" "B.Paste")
			(net "GND")
			(options
				(clearance outline)
				(anchor circle)
			)
			(primitives
				(gr_poly
					(pts
						(arc
							(start -0.254 0.1778)
							(mid -0.239121 0.213721)
							(end -0.2032 0.2286)
						)
						(arc
							(start 0.2032 0.2286)
							(mid 0.239121 0.213721)
							(end 0.254 0.1778)
						)
						(arc
							(start 0.254 -0.1778)
							(mid 0.239121 -0.213721)
							(end 0.2032 -0.2286)
						)
						(arc
							(start -0.2032 -0.2286)
							(mid -0.239121 -0.213721)
							(end -0.254 -0.1778)
						)
					)
					(width 0)
					(fill yes)
				)
			)
		)
	)
	(footprint ""
		(layer "B.Cu")
		(at 89.662 -36.068)
		(property "Reference" "C121"
			(at 0 0 0)
			(layer "B.SilkS")
			(hide yes)
			(effects
				(font
					(size 1.27 1.27)
				)
				(justify mirror)
			)
		)
		(property "Value" "SCD1U16V2KX-3GP"
			(at -1.1811 -2.7051 0)
			(unlocked yes)
			(layer "B.Fab")
			(hide yes)
			(effects
				(font
					(size 1.016 1.016)
					(thickness 0.1524)
				)
				(justify mirror)
			)
		)
		(property "Device Type" "C402H22"
			(at -1.1811 -4.2291 0)
			(unlocked yes)
			(layer "B.Fab")
			(hide yes)
			(effects
				(font
					(size 1.016 1.016)
					(thickness 0.1524)
				)
				(justify mirror)
			)
		)
		(duplicate_pad_numbers_are_jumpers no)
		(fp_rect
			(start 0.381 0.7366)
			(end -0.381 -0.7366)
			(stroke
				(width 0)
				(type default)
			)
			(fill no)
			(layer "B.CrtYd")
		)
		(fp_rect
			(start 0.381 0.7366)
			(end -0.381 -0.7366)
			(stroke
				(width 0)
				(type default)
			)
			(fill no)
			(layer "B.Fab")
		)
		(pad "1" smd custom
			(at 0 -0.4572 180)
			(size 0.1143 0.1143)
			(layers "B.Cu" "B.Mask" "B.Paste")
			(net "P3V3_CPU")
			(options
				(clearance outline)
				(anchor circle)
			)
			(primitives
				(gr_poly
					(pts
						(arc
							(start -0.254 0.1778)
							(mid -0.239121 0.213721)
							(end -0.2032 0.2286)
						)
						(arc
							(start 0.2032 0.2286)
							(mid 0.239121 0.213721)
							(end 0.254 0.1778)
						)
						(arc
							(start 0.254 -0.1778)
							(mid 0.239121 -0.213721)
							(end 0.2032 -0.2286)
						)
						(arc
							(start -0.2032 -0.2286)
							(mid -0.239121 -0.213721)
							(end -0.254 -0.1778)
						)
					)
					(width 0)
					(fill yes)
				)
			)
		)
		(pad "2" smd custom
			(at 0 0.4572 180)
			(size 0.1143 0.1143)
			(layers "B.Cu" "B.Mask" "B.Paste")
			(net "GND")
			(options
				(clearance outline)
				(anchor circle)
			)
			(primitives
				(gr_poly
					(pts
						(arc
							(start -0.254 0.1778)
							(mid -0.239121 0.213721)
							(end -0.2032 0.2286)
						)
						(arc
							(start 0.2032 0.2286)
							(mid 0.239121 0.213721)
							(end 0.254 0.1778)
						)
						(arc
							(start 0.254 -0.1778)
							(mid 0.239121 -0.213721)
							(end 0.2032 -0.2286)
						)
						(arc
							(start -0.2032 -0.2286)
							(mid -0.239121 -0.213721)
							(end -0.254 -0.1778)
						)
					)
					(width 0)
					(fill yes)
				)
			)
		)
	)
	(footprint ""
		(layer "B.Cu")
		(at 103.759 -14.097 -90)
		(property "Reference" "R477"
			(at 0 0 90)
			(layer "B.SilkS")
			(hide yes)
			(effects
				(font
					(size 1.27 1.27)
				)
				(justify mirror)
			)
		)
		(property "Value" "10KR2F-2-GP"
			(at -1.7907 -1.1176 270)
			(unlocked yes)
			(layer "B.Fab")
			(hide yes)
			(effects
				(font
					(size 1.016 1.016)
					(thickness 0.1524)
				)
				(justify mirror)
			)
		)
		(property "Device Type" "R402H16"
			(at -1.7907 -2.6416 270)
			(unlocked yes)
			(layer "B.Fab")
			(hide yes)
			(effects
				(font
					(size 1.016 1.016)
					(thickness 0.1524)
				)
				(justify mirror)
			)
		)
		(duplicate_pad_numbers_are_jumpers no)
		(fp_rect
			(start 0.381 0.8382)
			(end -0.381 -0.8382)
			(stroke
				(width 0)
				(type default)
			)
			(fill no)
			(layer "B.CrtYd")
		)
		(fp_rect
			(start 0.381 0.8382)
			(end -0.381 -0.8382)
			(stroke
				(width 0)
				(type default)
			)
			(fill no)
			(layer "B.Fab")
		)
		(pad "1" smd custom
			(at 0 -0.4318 90)
			(size 0.127 0.127)
			(layers "B.Cu" "B.Mask" "B.Paste")
			(net "P3V3")
			(options
				(clearance outline)
				(anchor circle)
			)
			(primitives
				(gr_poly
					(pts
						(arc
							(start -0.2032 0.2794)
							(mid -0.239121 0.264521)
							(end -0.254 0.2286)
						)
						(arc
							(start -0.254 -0.2286)
							(mid -0.239121 -0.264521)
							(end -0.2032 -0.2794)
						)
						(arc
							(start 0.2032 -0.2794)
							(mid 0.239121 -0.264521)
							(end 0.254 -0.2286)
						)
						(arc
							(start 0.254 0.2286)
							(mid 0.239121 0.264521)
							(end 0.2032 0.2794)
						)
					)
					(width 0)
					(fill yes)
				)
			)
		)
		(pad "2" smd custom
			(at 0 0.4318 90)
			(size 0.127 0.127)
			(layers "B.Cu" "B.Mask" "B.Paste")
			(net "IRQ_CPU_IERR#")
			(options
				(clearance outline)
				(anchor circle)
			)
			(primitives
				(gr_poly
					(pts
						(arc
							(start -0.2032 0.2794)
							(mid -0.239121 0.264521)
							(end -0.254 0.2286)
						)
						(arc
							(start -0.254 -0.2286)
							(mid -0.239121 -0.264521)
							(end -0.2032 -0.2794)
						)
						(arc
							(start 0.2032 -0.2794)
							(mid 0.239121 -0.264521)
							(end 0.254 -0.2286)
						)
						(arc
							(start 0.254 0.2286)
							(mid 0.239121 0.264521)
							(end 0.2032 0.2794)
						)
					)
					(width 0)
					(fill yes)
				)
			)
		)
	)
	(footprint ""
		(layer "B.Cu")
		(at 94.3864 -32.5374 -90)
		(property "Reference" "R350"
			(at 0 0 90)
			(layer "B.SilkS")
			(hide yes)
			(effects
				(font
					(size 1.27 1.27)
				)
				(justify mirror)
			)
		)
		(property "Value" "162R2F-GP"
			(at -0.064008 -3.993896 270)
			(unlocked yes)
			(layer "B.Fab")
			(hide yes)
			(effects
				(font
					(size 1.016 1.016)
					(thickness 0.1524)
				)
				(justify mirror)
			)
		)
		(property "Device Type" "R402H16"
			(at -0.064008 -5.517896 270)
			(unlocked yes)
			(layer "B.Fab")
			(hide yes)
			(effects
				(font
					(size 1.016 1.016)
					(thickness 0.1524)
				)
				(justify mirror)
			)
		)
		(duplicate_pad_numbers_are_jumpers no)
		(fp_rect
			(start 0.381 0.8382)
			(end -0.381 -0.8382)
			(stroke
				(width 0)
				(type default)
			)
			(fill no)
			(layer "B.CrtYd")
		)
		(fp_rect
			(start 0.381 0.8382)
			(end -0.381 -0.8382)
			(stroke
				(width 0)
				(type default)
			)
			(fill no)
			(layer "B.Fab")
		)
		(pad "1" smd custom
			(at 0 -0.4318 90)
			(size 0.127 0.127)
			(layers "B.Cu" "B.Mask" "B.Paste")
			(net "M_B_ODTPU")
			(options
				(clearance outline)
				(anchor circle)
			)
			(primitives
				(gr_poly
					(pts
						(arc
							(start -0.2032 0.2794)
							(mid -0.239121 0.264521)
							(end -0.254 0.2286)
						)
						(arc
							(start -0.254 -0.2286)
							(mid -0.239121 -0.264521)
							(end -0.2032 -0.2794)
						)
						(arc
							(start 0.2032 -0.2794)
							(mid 0.239121 -0.264521)
							(end 0.254 -0.2286)
						)
						(arc
							(start 0.254 0.2286)
							(mid 0.239121 0.264521)
							(end 0.2032 0.2794)
						)
					)
					(width 0)
					(fill yes)
				)
			)
		)
		(pad "2" smd custom
			(at 0 0.4318 90)
			(size 0.127 0.127)
			(layers "B.Cu" "B.Mask" "B.Paste")
			(net "GND")
			(options
				(clearance outline)
				(anchor circle)
			)
			(primitives
				(gr_poly
					(pts
						(arc
							(start -0.2032 0.2794)
							(mid -0.239121 0.264521)
							(end -0.254 0.2286)
						)
						(arc
							(start -0.254 -0.2286)
							(mid -0.239121 -0.264521)
							(end -0.2032 -0.2794)
						)
						(arc
							(start 0.2032 -0.2794)
							(mid 0.239121 -0.264521)
							(end 0.254 -0.2286)
						)
						(arc
							(start 0.254 0.2286)
							(mid 0.239121 0.264521)
							(end 0.2032 0.2794)
						)
					)
					(width 0)
					(fill yes)
				)
			)
		)
	)
	(footprint ""
		(layer "B.Cu")
		(at 91.948 -64.643 -90)
		(property "Reference" "PC21"
			(at 0 0 90)
			(layer "B.SilkS")
			(hide yes)
			(effects
				(font
					(size 1.27 1.27)
				)
				(justify mirror)
			)
		)
		(property "Value" "SC10U6D3V5KX-4GP"
			(at 0.0762 -6.1214 270)
			(unlocked yes)
			(layer "B.Fab")
			(hide yes)
			(effects
				(font
					(size 1.016 1.016)
					(thickness 0.1524)
				)
				(justify mirror)
			)
		)
		(property "Device Type" "C805H58"
			(at 0.0762 -8.1534 270)
			(unlocked yes)
			(layer "B.Fab")
			(hide yes)
			(effects
				(font
					(size 1.016 1.016)
					(thickness 0.1524)
				)
				(justify mirror)
			)
		)
		(duplicate_pad_numbers_are_jumpers no)
		(fp_line
			(start -0.6096 0)
			(end 0.6096 0)
			(stroke
				(width 0.3048)
				(type default)
			)
			(layer "B.SilkS")
		)
		(fp_poly
			(pts
				(xy 0.9017 1.4351) (xy -0.9017 1.4351) (xy -0.9017 -1.4351) (xy 0.9017 -1.4351)
			)
			(stroke
				(width 0)
				(type default)
			)
			(fill no)
			(layer "B.CrtYd")
		)
		(fp_poly
			(pts
				(xy -0.9017 1.4351) (xy -0.9017 -1.4351) (xy 0.9017 -1.4351) (xy 0.9017 1.4351)
			)
			(stroke
				(width 0)
				(type default)
			)
			(fill no)
			(layer "B.Fab")
		)
		(pad "1" smd rect
			(at 0 -0.8382 90)
			(size 1.5494 0.9398)
			(layers "B.Cu" "B.Mask" "B.Paste")
			(net "P1V1")
		)
		(pad "2" smd rect
			(at 0 0.8382 90)
			(size 1.5494 0.9398)
			(layers "B.Cu" "B.Mask" "B.Paste")
			(net "GND")
		)
	)
)
